(kicad_pcb
	(version 20260206)
	(generator "pcbnew")
	(generator_version "10.0")
	(general
		(thickness 1.6)
		(legacy_teardrops no)
	)
	(paper "A4")
	(title_block
		(title "04192023_DAF0TMB3IC0_F0TG_MB_C_brd_V02_OCP.brd")
		(comment 1 "Grand Teton / footprint 2783 of 8354 (U26), pads 4672-4788 of 6102")
	)
	(layers
		(0 "F.Cu" signal "TOP")
		(4 "In1.Cu" signal "GND")
		(6 "In2.Cu" signal "IN1")
		(8 "In3.Cu" signal "GND1")
		(10 "In4.Cu" signal "IN2")
		(12 "In5.Cu" signal "GND2")
		(14 "In6.Cu" signal "IN3")
		(16 "In7.Cu" signal "GND3")
		(18 "In8.Cu" signal "VCC")
		(20 "In9.Cu" signal "VCC1")
		(22 "In10.Cu" signal "GND4")
		(24 "In11.Cu" signal "IN4")
		(26 "In12.Cu" signal "GND5")
		(28 "In13.Cu" signal "IN5")
		(30 "In14.Cu" signal "GND6")
		(32 "In15.Cu" signal "IN6")
		(34 "In16.Cu" signal "GND7")
		(2 "B.Cu" signal "BOTTOM")
		(9 "F.Adhes" user "F.Adhesive")
		(11 "B.Adhes" user "B.Adhesive")
		(13 "F.Paste" user "Package Geometry/Pastemask Top")
		(15 "B.Paste" user "Package Geometry/Pastemask Bottom")
		(5 "F.SilkS" user "Ref Des/Silkscreen Top")
		(7 "B.SilkS" user "Ref Des/Silkscreen Bottom")
		(1 "F.Mask" user "Board Geometry/Soldermask Top")
		(3 "B.Mask" user "Board Geometry/Soldermask Bottom")
		(17 "Dwgs.User" user "User.Drawings")
		(19 "Cmts.User" user "User.Comments")
		(21 "Eco1.User" user "User.Eco1")
		(23 "Eco2.User" user "User.Eco2")
		(25 "Edge.Cuts" user "Board Geometry/Outline")
		(27 "Margin" user)
		(31 "F.CrtYd" user "Package Geometry/Place Bound Top")
		(29 "B.CrtYd" user "Package Geometry/Place Bound Bottom")
		(35 "F.Fab" user "Ref Des/Assembly Top")
		(33 "B.Fab" user "Ref Des/Assembly Bottom")
	)
	(footprint ""
		(layer "F.Cu")
		(at 111.927894 -258.880356 180)
		(property "Reference" "U26"
			(at -45.05579 -61.794136 0)
			(unlocked yes)
			(layer "F.SilkS")
			(effects
				(font
					(size 0.7874 0.5842)
					(thickness 0.1524)
				)
			)
		)
		(property "Value" ""
			(at 0 0 180)
			(layer "F.Fab")
			(effects
				(font
					(size 1.27 1.27)
				)
			)
		)
		(duplicate_pad_numbers_are_jumpers no)
		(pad "DE67" smd circle
			(at 26.640028 33.56991 180)
			(size 0.450088 0.450088)
			(layers "F.Cu" "F.Mask" "F.Paste")
			(net "M_F_CPU1_SB_DQ<30>")
		)
		(pad "DE68" smd circle
			(at 27.580082 33.56991 180)
			(size 0.450088 0.450088)
			(layers "F.Cu" "F.Mask" "F.Paste")
			(net "GND")
		)
		(pad "DE69" smd circle
			(at 28.519882 33.56991 180)
			(size 0.450088 0.450088)
			(layers "F.Cu" "F.Mask" "F.Paste")
			(net "M_E_CPU1_SB_DQ<29>")
		)
		(pad "DE70" smd circle
			(at 29.459936 33.56991 180)
			(size 0.450088 0.450088)
			(layers "F.Cu" "F.Mask" "F.Paste")
			(net "GND")
		)
		(pad "DE71" smd circle
			(at 30.39999 33.56991 180)
			(size 0.450088 0.450088)
			(layers "F.Cu" "F.Mask" "F.Paste")
			(net "M_E_CPU1_SB_DQ<30>")
		)
		(pad "DE72" smd circle
			(at 31.340044 33.56991 180)
			(size 0.450088 0.450088)
			(layers "F.Cu" "F.Mask" "F.Paste")
			(net "PVDDIO_P1")
		)
		(pad "DE73" smd circle
			(at 32.280098 33.56991 180)
			(size 0.450088 0.450088)
			(layers "F.Cu" "F.Mask" "F.Paste")
			(net "M_A_CPU1_SB_DQ<29>")
		)
		(pad "DE74" smd circle
			(at 33.219898 33.56991 180)
			(size 0.450088 0.450088)
			(layers "F.Cu" "F.Mask" "F.Paste")
			(net "M_A_CPU1_SB_DQ<30>")
		)
		(pad "DE75" smd circle
			(at 34.159952 33.56991 180)
			(size 0.450088 0.450088)
			(layers "F.Cu" "F.Mask" "F.Paste")
			(net "GND")
		)
		(pad "DF2" smd circle
			(at -33.990026 34.379916 180)
			(size 0.450088 0.450088)
			(layers "F.Cu" "F.Mask" "F.Paste")
			(net "M_G_CPU1_SB_DQ<31>")
		)
		(pad "DF3" smd circle
			(at -33.049972 34.379916 180)
			(size 0.450088 0.450088)
			(layers "F.Cu" "F.Mask" "F.Paste")
			(net "GND")
		)
		(pad "DF4" smd circle
			(at -32.109918 34.379916 180)
			(size 0.450088 0.450088)
			(layers "F.Cu" "F.Mask" "F.Paste")
			(net "GND")
		)
		(pad "DF5" smd circle
			(at -31.170118 34.379916 180)
			(size 0.450088 0.450088)
			(layers "F.Cu" "F.Mask" "F.Paste")
			(net "GND")
		)
		(pad "DF6" smd circle
			(at -30.230064 34.379916 180)
			(size 0.450088 0.450088)
			(layers "F.Cu" "F.Mask" "F.Paste")
			(net "GND")
		)
		(pad "DF7" smd circle
			(at -29.29001 34.379916 180)
			(size 0.450088 0.450088)
			(layers "F.Cu" "F.Mask" "F.Paste")
			(net "M_K_CPU1_SB_DQ<31>")
		)
		(pad "DF8" smd circle
			(at -28.349956 34.379916 180)
			(size 0.450088 0.450088)
			(layers "F.Cu" "F.Mask" "F.Paste")
			(net "GND")
		)
		(pad "DF9" smd circle
			(at -27.409902 34.379916 180)
			(size 0.450088 0.450088)
			(layers "F.Cu" "F.Mask" "F.Paste")
			(net "M_L_CPU1_SB_DQ<31>")
		)
		(pad "DF10" smd circle
			(at -26.470102 34.379916 180)
			(size 0.450088 0.450088)
			(layers "F.Cu" "F.Mask" "F.Paste")
			(net "GND")
		)
		(pad "DF11" smd circle
			(at -25.530048 34.379916 180)
			(size 0.450088 0.450088)
			(layers "F.Cu" "F.Mask" "F.Paste")
			(net "GND")
		)
		(pad "DF12" smd circle
			(at -24.589994 34.379916 180)
			(size 0.450088 0.450088)
			(layers "F.Cu" "F.Mask" "F.Paste")
			(net "GND")
		)
		(pad "DF13" smd circle
			(at -23.64994 34.379916 180)
			(size 0.450088 0.450088)
			(layers "F.Cu" "F.Mask" "F.Paste")
			(net "GND")
		)
		(pad "DF14" smd circle
			(at -22.709886 34.379916 180)
			(size 0.450088 0.450088)
			(layers "F.Cu" "F.Mask" "F.Paste")
			(net "M_H_CPU1_SB_DQ<31>")
		)
		(pad "DF15" smd circle
			(at -21.770086 34.379916 180)
			(size 0.450088 0.450088)
			(layers "F.Cu" "F.Mask" "F.Paste")
			(net "GND")
		)
		(pad "DF16" smd circle
			(at -20.830032 34.379916 180)
			(size 0.450088 0.450088)
			(layers "F.Cu" "F.Mask" "F.Paste")
			(net "M_J_CPU1_SB_DQ<31>")
		)
		(pad "DF17" smd circle
			(at -19.889978 34.379916 180)
			(size 0.450088 0.450088)
			(layers "F.Cu" "F.Mask" "F.Paste")
			(net "GND")
		)
		(pad "DF18" smd circle
			(at -18.949924 34.379916 180)
			(size 0.450088 0.450088)
			(layers "F.Cu" "F.Mask" "F.Paste")
			(net "GND")
		)
		(pad "DF19" smd circle
			(at -18.010124 34.379916 180)
			(size 0.450088 0.450088)
			(layers "F.Cu" "F.Mask" "F.Paste")
			(net "GND")
		)
		(pad "DF20" smd circle
			(at -17.07007 34.379916 180)
			(size 0.450088 0.450088)
			(layers "F.Cu" "F.Mask" "F.Paste")
			(net "GND")
		)
		(pad "DF21" smd circle
			(at -16.130016 34.379916 180)
			(size 0.450088 0.450088)
			(layers "F.Cu" "F.Mask" "F.Paste")
			(net "M_I_CPU1_SB_DQ<31>")
		)
		(pad "DF22" smd circle
			(at -15.189962 34.379916 180)
			(size 0.450088 0.450088)
			(layers "F.Cu" "F.Mask" "F.Paste")
			(net "GND")
		)
		(pad "DF23" smd circle
			(at -14.249908 34.379916 180)
			(size 0.450088 0.450088)
			(layers "F.Cu" "F.Mask" "F.Paste")
			(net "GND")
		)
		(pad "DF24" smd circle
			(at -13.310108 34.379916 180)
			(size 0.450088 0.450088)
			(layers "F.Cu" "F.Mask" "F.Paste")
			(net "Net_2108")
		)
		(pad "DF25" smd circle
			(at -12.370054 34.379916 180)
			(size 0.450088 0.450088)
			(layers "F.Cu" "F.Mask" "F.Paste")
			(net "Net_2111")
		)
		(pad "DF26" smd circle
			(at -11.43 34.379916 180)
			(size 0.450088 0.450088)
			(layers "F.Cu" "F.Mask" "F.Paste")
			(net "GND")
		)
		(pad "DF27" smd circle
			(at -10.489946 34.379916 180)
			(size 0.450088 0.450088)
			(layers "F.Cu" "F.Mask" "F.Paste")
			(net "PD_ESPI_CPU1_CLK2")
		)
		(pad "DF28" smd circle
			(at -9.549892 34.379916 180)
			(size 0.450088 0.450088)
			(layers "F.Cu" "F.Mask" "F.Paste")
			(net "Net_2104")
		)
		(pad "DF29" smd circle
			(at -8.610092 34.379916 180)
			(size 0.450088 0.450088)
			(layers "F.Cu" "F.Mask" "F.Paste")
			(net "GND")
		)
		(pad "DF30" smd circle
			(at -7.670038 34.379916 180)
			(size 0.450088 0.450088)
			(layers "F.Cu" "F.Mask" "F.Paste")
			(net "Net_2118")
		)
		(pad "DF31" smd circle
			(at -6.729984 34.379916 180)
			(size 0.450088 0.450088)
			(layers "F.Cu" "F.Mask" "F.Paste")
			(net "Net_2077")
		)
		(pad "DF32" smd circle
			(at -5.78993 34.379916 180)
			(size 0.450088 0.450088)
			(layers "F.Cu" "F.Mask" "F.Paste")
			(net "GND")
		)
		(pad "DF33" smd circle
			(at -4.849876 34.379916 180)
			(size 0.450088 0.450088)
			(layers "F.Cu" "F.Mask" "F.Paste")
			(net "TP_SLOT2_BUF_SKU_ID0")
		)
		(pad "DF34" smd circle
			(at -3.910076 34.379916 180)
			(size 0.450088 0.450088)
			(layers "F.Cu" "F.Mask" "F.Paste")
			(net "TP_CPU1_UART0_RTS_N")
		)
		(pad "DF35" smd circle
			(at -2.970022 34.379916 180)
			(size 0.450088 0.450088)
			(layers "F.Cu" "F.Mask" "F.Paste")
			(net "GND")
		)
		(pad "DF36" smd circle
			(at -2.029968 34.379916 180)
			(size 0.450088 0.450088)
			(layers "F.Cu" "F.Mask" "F.Paste")
			(net "Net_2084")
		)
		(pad "DF37" smd circle
			(at -1.089914 34.379916 180)
			(size 0.450088 0.450088)
			(layers "F.Cu" "F.Mask" "F.Paste")
			(net "GND")
		)
		(pad "DF39" smd circle
			(at 0.78994 34.379916 180)
			(size 0.450088 0.450088)
			(layers "F.Cu" "F.Mask" "F.Paste")
			(net "GND")
		)
		(pad "DF40" smd circle
			(at 1.729994 34.379916 180)
			(size 0.450088 0.450088)
			(layers "F.Cu" "F.Mask" "F.Paste")
			(net "IRQ_CPU_BMC_NMI_N")
		)
		(pad "DF41" smd circle
			(at 2.670048 34.379916 180)
			(size 0.450088 0.450088)
			(layers "F.Cu" "F.Mask" "F.Paste")
			(net "Net_2171")
		)
		(pad "DF42" smd circle
			(at 3.610102 34.379916 180)
			(size 0.450088 0.450088)
			(layers "F.Cu" "F.Mask" "F.Paste")
			(net "GND")
		)
		(pad "DF43" smd circle
			(at 4.549902 34.379916 180)
			(size 0.450088 0.450088)
			(layers "F.Cu" "F.Mask" "F.Paste")
			(net "GND")
		)
		(pad "DF44" smd circle
			(at 5.489956 34.379916 180)
			(size 0.450088 0.450088)
			(layers "F.Cu" "F.Mask" "F.Paste")
			(net "GND")
		)
		(pad "DF45" smd circle
			(at 6.43001 34.379916 180)
			(size 0.450088 0.450088)
			(layers "F.Cu" "F.Mask" "F.Paste")
			(net "GND")
		)
		(pad "DF46" smd circle
			(at 7.370064 34.379916 180)
			(size 0.450088 0.450088)
			(layers "F.Cu" "F.Mask" "F.Paste")
			(net "GND")
		)
		(pad "DF47" smd circle
			(at 8.310118 34.379916 180)
			(size 0.450088 0.450088)
			(layers "F.Cu" "F.Mask" "F.Paste")
			(net "GND")
		)
		(pad "DF48" smd circle
			(at 9.249918 34.379916 180)
			(size 0.450088 0.450088)
			(layers "F.Cu" "F.Mask" "F.Paste")
			(net "GND")
		)
		(pad "DF49" smd circle
			(at 10.189972 34.379916 180)
			(size 0.450088 0.450088)
			(layers "F.Cu" "F.Mask" "F.Paste")
			(net "GND")
		)
		(pad "DF50" smd circle
			(at 11.130026 34.379916 180)
			(size 0.450088 0.450088)
			(layers "F.Cu" "F.Mask" "F.Paste")
			(net "GND")
		)
		(pad "DF51" smd circle
			(at 12.07008 34.379916 180)
			(size 0.450088 0.450088)
			(layers "F.Cu" "F.Mask" "F.Paste")
			(net "GND")
		)
		(pad "DF52" smd circle
			(at 13.00988 34.379916 180)
			(size 0.450088 0.450088)
			(layers "F.Cu" "F.Mask" "F.Paste")
			(net "GND")
		)
		(pad "DF53" smd circle
			(at 13.949934 34.379916 180)
			(size 0.450088 0.450088)
			(layers "F.Cu" "F.Mask" "F.Paste")
			(net "GND")
		)
		(pad "DF54" smd circle
			(at 14.889988 34.379916 180)
			(size 0.450088 0.450088)
			(layers "F.Cu" "F.Mask" "F.Paste")
			(net "GND")
		)
		(pad "DF55" smd circle
			(at 15.830042 34.379916 180)
			(size 0.450088 0.450088)
			(layers "F.Cu" "F.Mask" "F.Paste")
			(net "M_C_CPU1_SB_DQ<31>")
		)
		(pad "DF56" smd circle
			(at 16.770096 34.379916 180)
			(size 0.450088 0.450088)
			(layers "F.Cu" "F.Mask" "F.Paste")
			(net "GND")
		)
		(pad "DF57" smd circle
			(at 17.709896 34.379916 180)
			(size 0.450088 0.450088)
			(layers "F.Cu" "F.Mask" "F.Paste")
			(net "GND")
		)
		(pad "DF58" smd circle
			(at 18.64995 34.379916 180)
			(size 0.450088 0.450088)
			(layers "F.Cu" "F.Mask" "F.Paste")
			(net "GND")
		)
		(pad "DF59" smd circle
			(at 19.590004 34.379916 180)
			(size 0.450088 0.450088)
			(layers "F.Cu" "F.Mask" "F.Paste")
			(net "GND")
		)
		(pad "DF60" smd circle
			(at 20.530058 34.379916 180)
			(size 0.450088 0.450088)
			(layers "F.Cu" "F.Mask" "F.Paste")
			(net "M_D_CPU1_SB_DQ<31>")
		)
		(pad "DF61" smd circle
			(at 21.470112 34.379916 180)
			(size 0.450088 0.450088)
			(layers "F.Cu" "F.Mask" "F.Paste")
			(net "GND")
		)
		(pad "DF62" smd circle
			(at 22.409912 34.379916 180)
			(size 0.450088 0.450088)
			(layers "F.Cu" "F.Mask" "F.Paste")
			(net "M_B_CPU1_SB_DQ<31>")
		)
		(pad "DF63" smd circle
			(at 23.349966 34.379916 180)
			(size 0.450088 0.450088)
			(layers "F.Cu" "F.Mask" "F.Paste")
			(net "GND")
		)
		(pad "DF64" smd circle
			(at 24.29002 34.379916 180)
			(size 0.450088 0.450088)
			(layers "F.Cu" "F.Mask" "F.Paste")
			(net "GND")
		)
		(pad "DF65" smd circle
			(at 25.230074 34.379916 180)
			(size 0.450088 0.450088)
			(layers "F.Cu" "F.Mask" "F.Paste")
			(net "GND")
		)
		(pad "DF66" smd circle
			(at 26.170128 34.379916 180)
			(size 0.450088 0.450088)
			(layers "F.Cu" "F.Mask" "F.Paste")
			(net "GND")
		)
		(pad "DF67" smd circle
			(at 27.109928 34.379916 180)
			(size 0.450088 0.450088)
			(layers "F.Cu" "F.Mask" "F.Paste")
			(net "M_F_CPU1_SB_DQ<31>")
		)
		(pad "DF68" smd circle
			(at 28.049982 34.379916 180)
			(size 0.450088 0.450088)
			(layers "F.Cu" "F.Mask" "F.Paste")
			(net "GND")
		)
		(pad "DF69" smd circle
			(at 28.990036 34.379916 180)
			(size 0.450088 0.450088)
			(layers "F.Cu" "F.Mask" "F.Paste")
			(net "M_E_CPU1_SB_DQ<31>")
		)
		(pad "DF70" smd circle
			(at 29.93009 34.379916 180)
			(size 0.450088 0.450088)
			(layers "F.Cu" "F.Mask" "F.Paste")
			(net "GND")
		)
		(pad "DF71" smd circle
			(at 30.86989 34.379916 180)
			(size 0.450088 0.450088)
			(layers "F.Cu" "F.Mask" "F.Paste")
			(net "GND")
		)
		(pad "DF72" smd circle
			(at 31.809944 34.379916 180)
			(size 0.450088 0.450088)
			(layers "F.Cu" "F.Mask" "F.Paste")
			(net "GND")
		)
		(pad "DF73" smd circle
			(at 32.749998 34.379916 180)
			(size 0.450088 0.450088)
			(layers "F.Cu" "F.Mask" "F.Paste")
			(net "GND")
		)
		(pad "DF74" smd circle
			(at 33.690052 34.379916 180)
			(size 0.450088 0.450088)
			(layers "F.Cu" "F.Mask" "F.Paste")
			(net "M_A_CPU1_SB_DQ<31>")
		)
		(pad "DG1" smd circle
			(at -34.459926 35.189922 180)
			(size 0.450088 0.450088)
			(layers "F.Cu" "F.Mask" "F.Paste")
			(net "GND")
		)
		(pad "DG2" smd circle
			(at -33.519872 35.189922 180)
			(size 0.450088 0.450088)
			(layers "F.Cu" "F.Mask" "F.Paste")
			(net "GND")
		)
		(pad "DG3" smd circle
			(at -32.580072 35.189922 180)
			(size 0.450088 0.450088)
			(layers "F.Cu" "F.Mask" "F.Paste")
			(net "VSENSE_PVDDCR_CPU1_P1_DP")
		)
		(pad "DG4" smd circle
			(at -31.640018 35.189922 180)
			(size 0.450088 0.450088)
			(layers "F.Cu" "F.Mask" "F.Paste")
			(net "CPU1_SLP_S5_N")
		)
		(pad "DG5" smd circle
			(at -30.699964 35.189922 180)
			(size 0.450088 0.450088)
			(layers "F.Cu" "F.Mask" "F.Paste")
			(net "PVDD11_S3_P1")
		)
		(pad "DG6" smd circle
			(at -29.75991 35.189922 180)
			(size 0.450088 0.450088)
			(layers "F.Cu" "F.Mask" "F.Paste")
			(net "GND")
		)
		(pad "DG7" smd circle
			(at -28.82011 35.189922 180)
			(size 0.450088 0.450088)
			(layers "F.Cu" "F.Mask" "F.Paste")
			(net "GND")
		)
		(pad "DG8" smd circle
			(at -27.880056 35.189922 180)
			(size 0.450088 0.450088)
			(layers "F.Cu" "F.Mask" "F.Paste")
			(net "GND")
		)
		(pad "DG9" smd circle
			(at -26.940002 35.189922 180)
			(size 0.450088 0.450088)
			(layers "F.Cu" "F.Mask" "F.Paste")
			(net "GND")
		)
		(pad "DG10" smd circle
			(at -25.999948 35.189922 180)
			(size 0.450088 0.450088)
			(layers "F.Cu" "F.Mask" "F.Paste")
			(net "RST_CPU1_RSMRST_N")
		)
		(pad "DG11" smd circle
			(at -25.059894 35.189922 180)
			(size 0.450088 0.450088)
			(layers "F.Cu" "F.Mask" "F.Paste")
			(net "Net_2086")
		)
		(pad "DG12" smd circle
			(at -24.120094 35.189922 180)
			(size 0.450088 0.450088)
			(layers "F.Cu" "F.Mask" "F.Paste")
			(net "Net_2092")
		)
		(pad "DG13" smd circle
			(at -23.18004 35.189922 180)
			(size 0.450088 0.450088)
			(layers "F.Cu" "F.Mask" "F.Paste")
			(net "GND")
		)
		(pad "DG14" smd circle
			(at -22.239986 35.189922 180)
			(size 0.450088 0.450088)
			(layers "F.Cu" "F.Mask" "F.Paste")
			(net "GND")
		)
		(pad "DG15" smd circle
			(at -21.299932 35.189922 180)
			(size 0.450088 0.450088)
			(layers "F.Cu" "F.Mask" "F.Paste")
			(net "GND")
		)
		(pad "DG16" smd circle
			(at -20.359878 35.189922 180)
			(size 0.450088 0.450088)
			(layers "F.Cu" "F.Mask" "F.Paste")
			(net "GND")
		)
		(pad "DG17" smd circle
			(at -19.420078 35.189922 180)
			(size 0.450088 0.450088)
			(layers "F.Cu" "F.Mask" "F.Paste")
			(net "Net_2163")
		)
		(pad "DG18" smd circle
			(at -18.480024 35.189922 180)
			(size 0.450088 0.450088)
			(layers "F.Cu" "F.Mask" "F.Paste")
			(net "GND")
		)
		(pad "DG19" smd circle
			(at -17.53997 35.189922 180)
			(size 0.450088 0.450088)
			(layers "F.Cu" "F.Mask" "F.Paste")
			(net "PVDDCR_CPU1_P1")
		)
		(pad "DG20" smd circle
			(at -16.599916 35.189922 180)
			(size 0.450088 0.450088)
			(layers "F.Cu" "F.Mask" "F.Paste")
			(net "GND")
		)
		(pad "DG21" smd circle
			(at -15.660116 35.189922 180)
			(size 0.450088 0.450088)
			(layers "F.Cu" "F.Mask" "F.Paste")
			(net "GND")
		)
		(pad "DG22" smd circle
			(at -14.720062 35.189922 180)
			(size 0.450088 0.450088)
			(layers "F.Cu" "F.Mask" "F.Paste")
			(net "Net_2105")
		)
		(pad "DG23" smd circle
			(at -13.780008 35.189922 180)
			(size 0.450088 0.450088)
			(layers "F.Cu" "F.Mask" "F.Paste")
			(net "Net_2113")
		)
		(pad "DG24" smd circle
			(at -12.839954 35.189922 180)
			(size 0.450088 0.450088)
			(layers "F.Cu" "F.Mask" "F.Paste")
			(net "GND")
		)
		(pad "DG25" smd circle
			(at -11.8999 35.189922 180)
			(size 0.450088 0.450088)
			(layers "F.Cu" "F.Mask" "F.Paste")
			(net "Net_2112")
		)
		(pad "DG26" smd circle
			(at -10.9601 35.189922 180)
			(size 0.450088 0.450088)
			(layers "F.Cu" "F.Mask" "F.Paste")
			(net "Net_2119")
		)
		(pad "DG27" smd circle
			(at -10.020046 35.189922 180)
			(size 0.450088 0.450088)
			(layers "F.Cu" "F.Mask" "F.Paste")
			(net "GND")
		)
		(pad "DG28" smd circle
			(at -9.079992 35.189922 180)
			(size 0.450088 0.450088)
			(layers "F.Cu" "F.Mask" "F.Paste")
			(net "Net_2114")
		)
		(pad "DG29" smd circle
			(at -8.139938 35.189922 180)
			(size 0.450088 0.450088)
			(layers "F.Cu" "F.Mask" "F.Paste")
			(net "Net_2107")
		)
		(pad "DG30" smd circle
			(at -7.199884 35.189922 180)
			(size 0.450088 0.450088)
			(layers "F.Cu" "F.Mask" "F.Paste")
			(net "GND")
		)
		(pad "DG31" smd circle
			(at -6.260084 35.189922 180)
			(size 0.450088 0.450088)
			(layers "F.Cu" "F.Mask" "F.Paste")
			(net "Net_2078")
		)
		(pad "DG32" smd circle
			(at -5.32003 35.189922 180)
			(size 0.450088 0.450088)
			(layers "F.Cu" "F.Mask" "F.Paste")
			(net "Net_2079")
		)
		(pad "DG33" smd circle
			(at -4.379976 35.189922 180)
			(size 0.450088 0.450088)
			(layers "F.Cu" "F.Mask" "F.Paste")
			(net "GND")
		)
		(pad "DG34" smd circle
			(at -3.439922 35.189922 180)
			(size 0.450088 0.450088)
			(layers "F.Cu" "F.Mask" "F.Paste")
			(net "TP_CPU1_UART0_INTR")
		)
		(pad "DG35" smd circle
			(at -2.500122 35.189922 180)
			(size 0.450088 0.450088)
			(layers "F.Cu" "F.Mask" "F.Paste")
			(net "TP_CPU1_UART0_RX")
		)
		(pad "DG36" smd circle
			(at -1.560068 35.189922 180)
			(size 0.450088 0.450088)
			(layers "F.Cu" "F.Mask" "F.Paste")
			(net "RST_CPU1_PERST1_N")
		)
	)
)
